(kicad_pcb
	(version 20260206)
	(generator "pcbnew")
	(generator_version "10.0")
	(general
		(thickness 1.6)
		(legacy_teardrops no)
	)
	(paper "A4")
	(title_block
		(title "v1-chassis-manager — T6M_CM_d_v01_1031_1645.brd")
		(comment 1 "Open CloudServer (Microsoft) / footprints 606-615 of 2512")
	)
	(layers
		(0 "F.Cu" signal "TOP")
		(4 "In1.Cu" signal "GND1")
		(6 "In2.Cu" signal "IN1")
		(8 "In3.Cu" signal "VCC1")
		(10 "In4.Cu" signal "VCC2")
		(12 "In5.Cu" signal "GND2")
		(14 "In6.Cu" signal "IN2")
		(16 "In7.Cu" signal "IN3")
		(18 "In8.Cu" signal "GND3")
		(2 "B.Cu" signal "BOTTOM")
		(9 "F.Adhes" user "F.Adhesive")
		(11 "B.Adhes" user "B.Adhesive")
		(13 "F.Paste" user "Package Geometry/Pastemask Top")
		(15 "B.Paste" user "Package Geometry/Pastemask Bottom")
		(5 "F.SilkS" user "Ref Des/Silkscreen Top")
		(7 "B.SilkS" user "Ref Des/Silkscreen Bottom")
		(1 "F.Mask" user "Board Geometry/Soldermask Top")
		(3 "B.Mask" user "Board Geometry/Soldermask Bottom")
		(17 "Dwgs.User" user "User.Drawings")
		(19 "Cmts.User" user "User.Comments")
		(21 "Eco1.User" user "User.Eco1")
		(23 "Eco2.User" user "User.Eco2")
		(25 "Edge.Cuts" user "Board Geometry/Outline")
		(27 "Margin" user)
		(31 "F.CrtYd" user "Package Geometry/Place Bound Top")
		(29 "B.CrtYd" user "Package Geometry/Place Bound Bottom")
		(35 "F.Fab" user "Ref Des/Assembly Top")
		(33 "B.Fab" user "Ref Des/Assembly Bottom")
	)
	(footprint ""
		(layer "F.Cu")
		(at 118.34876 -175.426624 90)
		(property "Reference" "R798"
			(at -57.046622 32.819848 90)
			(unlocked yes)
			(layer "F.SilkS")
			(effects
				(font
					(size 0.7874 0.5842)
					(thickness 0.1524)
				)
				(justify left)
			)
		)
		(property "Value" ""
			(at 0 0 90)
			(layer "F.Fab")
			(effects
				(font
					(size 1.27 1.27)
				)
			)
		)
		(duplicate_pad_numbers_are_jumpers no)
		(fp_line
			(start 0.7874 -0.4064)
			(end 0.7874 0.4064)
			(stroke
				(width 0.1524)
				(type default)
			)
			(layer "F.SilkS")
		)
		(fp_line
			(start -0.7874 -0.4064)
			(end 0.7874 -0.4064)
			(stroke
				(width 0.1524)
				(type default)
			)
			(layer "F.SilkS")
		)
		(fp_line
			(start 0.7874 0.4064)
			(end -0.7874 0.4064)
			(stroke
				(width 0.1524)
				(type default)
			)
			(layer "F.SilkS")
		)
		(fp_line
			(start -0.7874 0.4064)
			(end -0.7874 -0.4064)
			(stroke
				(width 0.1524)
				(type default)
			)
			(layer "F.SilkS")
		)
		(fp_poly
			(pts
				(xy -0.508 0.2794) (xy -0.508 0.2286) (xy -0.635 0.2286) (xy -0.635 -0.254) (xy -0.5334 -0.254)
				(xy -0.5334 -0.2794) (xy 0.5334 -0.2794) (xy 0.5334 -0.254) (xy 0.635 -0.254) (xy 0.635 0.254) (xy 0.5334 0.254)
				(xy 0.5334 0.2794)
			)
			(stroke
				(width 0)
				(type default)
			)
			(fill no)
			(layer "F.CrtYd")
		)
		(pad "1" smd rect
			(at 0.40005 0 90)
			(size 0.4572 0.508)
			(layers "F.Cu" "F.Mask" "F.Paste")
			(net "N31328107")
		)
		(pad "2" smd rect
			(at -0.40005 0 90)
			(size 0.4572 0.508)
			(layers "F.Cu" "F.Mask" "F.Paste")
			(net "GND")
		)
	)
	(footprint ""
		(layer "F.Cu")
		(at 152.755854 -138.203432)
		(property "Reference" "R1067"
			(at -5.190236 1.955546 0)
			(unlocked yes)
			(layer "F.SilkS")
			(effects
				(font
					(size 0.7874 0.5842)
					(thickness 0.1524)
				)
				(justify left)
			)
		)
		(property "Value" ""
			(at 0 0 0)
			(layer "F.Fab")
			(effects
				(font
					(size 1.27 1.27)
				)
			)
		)
		(duplicate_pad_numbers_are_jumpers no)
		(fp_line
			(start -0.7874 -0.4064)
			(end 0.7874 -0.4064)
			(stroke
				(width 0.1524)
				(type default)
			)
			(layer "F.SilkS")
		)
		(fp_line
			(start -0.7874 0.4064)
			(end -0.7874 -0.4064)
			(stroke
				(width 0.1524)
				(type default)
			)
			(layer "F.SilkS")
		)
		(fp_line
			(start 0.7874 -0.4064)
			(end 0.7874 0.4064)
			(stroke
				(width 0.1524)
				(type default)
			)
			(layer "F.SilkS")
		)
		(fp_line
			(start 0.7874 0.4064)
			(end -0.7874 0.4064)
			(stroke
				(width 0.1524)
				(type default)
			)
			(layer "F.SilkS")
		)
		(fp_poly
			(pts
				(xy -0.508 0.2794) (xy -0.508 0.2286) (xy -0.635 0.2286) (xy -0.635 -0.254) (xy -0.5334 -0.254)
				(xy -0.5334 -0.2794) (xy 0.5334 -0.2794) (xy 0.5334 -0.254) (xy 0.635 -0.254) (xy 0.635 0.254) (xy 0.5334 0.254)
				(xy 0.5334 0.2794)
			)
			(stroke
				(width 0)
				(type default)
			)
			(fill no)
			(layer "F.CrtYd")
		)
		(pad "1" smd rect
			(at 0.40005 0)
			(size 0.4572 0.508)
			(layers "F.Cu" "F.Mask" "F.Paste")
			(net "RST_BTN_NODE1_C_L")
		)
		(pad "2" smd rect
			(at -0.40005 0)
			(size 0.4572 0.508)
			(layers "F.Cu" "F.Mask" "F.Paste")
			(net "RST_BTN_NODE1_L")
		)
	)
	(footprint ""
		(layer "F.Cu")
		(at 41.896792 -3.661918 90)
		(property "Reference" "PC74"
			(at -3.08229 -13.164566 90)
			(unlocked yes)
			(layer "F.SilkS")
			(effects
				(font
					(size 0.7874 0.5842)
					(thickness 0.1524)
				)
				(justify left)
			)
		)
		(property "Value" ""
			(at 0 0 90)
			(layer "F.Fab")
			(effects
				(font
					(size 1.27 1.27)
				)
			)
		)
		(duplicate_pad_numbers_are_jumpers no)
		(fp_line
			(start 2.2098 -0.9398)
			(end 2.2098 0.9398)
			(stroke
				(width 0.1524)
				(type default)
			)
			(layer "F.SilkS")
		)
		(fp_line
			(start 0 -0.9398)
			(end 0 0.9398)
			(stroke
				(width 0.1524)
				(type default)
			)
			(layer "F.SilkS")
		)
		(fp_line
			(start -2.2098 -0.9398)
			(end 2.2098 -0.9398)
			(stroke
				(width 0.1524)
				(type default)
			)
			(layer "F.SilkS")
		)
		(fp_line
			(start 2.2098 0.9398)
			(end -2.2098 0.9398)
			(stroke
				(width 0.1524)
				(type default)
			)
			(layer "F.SilkS")
		)
		(fp_line
			(start -2.2098 0.9398)
			(end -2.2098 -0.9398)
			(stroke
				(width 0.1524)
				(type default)
			)
			(layer "F.SilkS")
		)
		(fp_poly
			(pts
				(xy -1.6764 0.889) (xy -1.6764 0.7874) (xy -2.0574 0.7874) (xy -2.0574 -0.7874) (xy -1.6764 -0.7874)
				(xy -1.6764 -0.9398) (xy 1.6764 -0.9398) (xy 1.6764 -0.7874) (xy 2.0574 -0.7874) (xy 2.0574 0.7874)
				(xy 1.6764 0.7874) (xy 1.6764 0.9398) (xy -1.6764 0.9398)
			)
			(stroke
				(width 0)
				(type default)
			)
			(fill no)
			(layer "F.CrtYd")
		)
		(fp_line
			(start 1.700022 -0.899922)
			(end 1.700022 0.899922)
			(stroke
				(width 0.1)
				(type default)
			)
			(layer "F.Fab")
		)
		(fp_line
			(start -1.700022 -0.899922)
			(end 1.700022 -0.899922)
			(stroke
				(width 0.1)
				(type default)
			)
			(layer "F.Fab")
		)
		(fp_line
			(start 1.700022 0.899922)
			(end -1.700022 0.899922)
			(stroke
				(width 0.1)
				(type default)
			)
			(layer "F.Fab")
		)
		(fp_line
			(start -1.700022 0.899922)
			(end -1.700022 -0.899922)
			(stroke
				(width 0.1)
				(type default)
			)
			(layer "F.Fab")
		)
		(pad "1" smd rect
			(at 1.4732 0 90)
			(size 1.1684 1.5748)
			(layers "F.Cu" "F.Mask" "F.Paste")
			(net "SW_PV_VDDR_NODE1_VIN_FLT")
		)
		(pad "2" smd rect
			(at -1.4732 0 90)
			(size 1.1684 1.5748)
			(layers "F.Cu" "F.Mask" "F.Paste")
			(net "GND")
		)
	)
	(footprint ""
		(layer "F.Cu")
		(at 175.554894 -130.63982 90)
		(property "Reference" "R1037"
			(at -1.213866 12.029948 90)
			(unlocked yes)
			(layer "F.SilkS")
			(effects
				(font
					(size 0.7874 0.5842)
					(thickness 0.1524)
				)
				(justify left)
			)
		)
		(property "Value" ""
			(at 0 0 90)
			(layer "F.Fab")
			(effects
				(font
					(size 1.27 1.27)
				)
			)
		)
		(duplicate_pad_numbers_are_jumpers no)
		(fp_line
			(start 0.7874 -0.4064)
			(end 0.7874 0.4064)
			(stroke
				(width 0.1524)
				(type default)
			)
			(layer "F.SilkS")
		)
		(fp_line
			(start -0.7874 -0.4064)
			(end 0.7874 -0.4064)
			(stroke
				(width 0.1524)
				(type default)
			)
			(layer "F.SilkS")
		)
		(fp_line
			(start 0.7874 0.4064)
			(end -0.7874 0.4064)
			(stroke
				(width 0.1524)
				(type default)
			)
			(layer "F.SilkS")
		)
		(fp_line
			(start -0.7874 0.4064)
			(end -0.7874 -0.4064)
			(stroke
				(width 0.1524)
				(type default)
			)
			(layer "F.SilkS")
		)
		(fp_poly
			(pts
				(xy -0.508 0.2794) (xy -0.508 0.2286) (xy -0.635 0.2286) (xy -0.635 -0.254) (xy -0.5334 -0.254)
				(xy -0.5334 -0.2794) (xy 0.5334 -0.2794) (xy 0.5334 -0.254) (xy 0.635 -0.254) (xy 0.635 0.254) (xy 0.5334 0.254)
				(xy 0.5334 0.2794)
			)
			(stroke
				(width 0)
				(type default)
			)
			(fill no)
			(layer "F.CrtYd")
		)
		(pad "1" smd rect
			(at 0.40005 0 90)
			(size 0.4572 0.508)
			(layers "F.Cu" "F.Mask" "F.Paste")
			(net "GND")
		)
		(pad "2" smd rect
			(at -0.40005 0 90)
			(size 0.4572 0.508)
			(layers "F.Cu" "F.Mask" "F.Paste")
			(net "FM_CPLD_NODE1_DEBUG_MODE")
		)
	)
	(footprint ""
		(layer "F.Cu")
		(at 60.312554 -164.534596 90)
		(property "Reference" "R1236"
			(at 1.509776 0.12954 90)
			(unlocked yes)
			(layer "F.SilkS")
			(effects
				(font
					(size 0.7874 0.5842)
					(thickness 0.1524)
				)
				(justify left)
			)
		)
		(property "Value" ""
			(at 0 0 90)
			(layer "F.Fab")
			(effects
				(font
					(size 1.27 1.27)
				)
			)
		)
		(duplicate_pad_numbers_are_jumpers no)
		(fp_line
			(start 0.7874 -0.4064)
			(end 0.7874 0.4064)
			(stroke
				(width 0.1524)
				(type default)
			)
			(layer "F.SilkS")
		)
		(fp_line
			(start -0.7874 -0.4064)
			(end 0.7874 -0.4064)
			(stroke
				(width 0.1524)
				(type default)
			)
			(layer "F.SilkS")
		)
		(fp_line
			(start 0.7874 0.4064)
			(end -0.7874 0.4064)
			(stroke
				(width 0.1524)
				(type default)
			)
			(layer "F.SilkS")
		)
		(fp_line
			(start -0.7874 0.4064)
			(end -0.7874 -0.4064)
			(stroke
				(width 0.1524)
				(type default)
			)
			(layer "F.SilkS")
		)
		(fp_poly
			(pts
				(xy -0.508 0.2794) (xy -0.508 0.2286) (xy -0.635 0.2286) (xy -0.635 -0.254) (xy -0.5334 -0.254)
				(xy -0.5334 -0.2794) (xy 0.5334 -0.2794) (xy 0.5334 -0.254) (xy 0.635 -0.254) (xy 0.635 0.254) (xy 0.5334 0.254)
				(xy 0.5334 0.2794)
			)
			(stroke
				(width 0)
				(type default)
			)
			(fill no)
			(layer "F.CrtYd")
		)
		(pad "1" smd rect
			(at 0.40005 0 90)
			(size 0.4572 0.508)
			(layers "F.Cu" "F.Mask" "F.Paste")
			(net "GND")
		)
		(pad "2" smd rect
			(at -0.40005 0 90)
			(size 0.4572 0.508)
			(layers "F.Cu" "F.Mask" "F.Paste")
			(net "FM_CPLD_NODE1_P5V_EN")
		)
	)
	(footprint ""
		(layer "F.Cu")
		(at 66.225166 -96.709992 90)
		(property "Reference" "R65"
			(at -54.98719 28.439364 90)
			(unlocked yes)
			(layer "F.SilkS")
			(effects
				(font
					(size 0.7874 0.5842)
					(thickness 0.1524)
				)
				(justify left)
			)
		)
		(property "Value" ""
			(at 0 0 90)
			(layer "F.Fab")
			(effects
				(font
					(size 1.27 1.27)
				)
			)
		)
		(duplicate_pad_numbers_are_jumpers no)
		(fp_line
			(start 0.7874 -0.4064)
			(end 0.7874 0.4064)
			(stroke
				(width 0.1524)
				(type default)
			)
			(layer "F.SilkS")
		)
		(fp_line
			(start -0.7874 -0.4064)
			(end 0.7874 -0.4064)
			(stroke
				(width 0.1524)
				(type default)
			)
			(layer "F.SilkS")
		)
		(fp_line
			(start 0.7874 0.4064)
			(end -0.7874 0.4064)
			(stroke
				(width 0.1524)
				(type default)
			)
			(layer "F.SilkS")
		)
		(fp_line
			(start -0.7874 0.4064)
			(end -0.7874 -0.4064)
			(stroke
				(width 0.1524)
				(type default)
			)
			(layer "F.SilkS")
		)
		(fp_poly
			(pts
				(xy -0.508 0.2794) (xy -0.508 0.2286) (xy -0.635 0.2286) (xy -0.635 -0.254) (xy -0.5334 -0.254)
				(xy -0.5334 -0.2794) (xy 0.5334 -0.2794) (xy 0.5334 -0.254) (xy 0.635 -0.254) (xy 0.635 0.254) (xy 0.5334 0.254)
				(xy 0.5334 0.2794)
			)
			(stroke
				(width 0)
				(type default)
			)
			(fill no)
			(layer "F.CrtYd")
		)
		(pad "1" smd rect
			(at 0.40005 0 90)
			(size 0.4572 0.508)
			(layers "F.Cu" "F.Mask" "F.Paste")
			(net "LPC_CPU_NODE1_FRAME_L")
		)
		(pad "2" smd rect
			(at -0.40005 0 90)
			(size 0.4572 0.508)
			(layers "F.Cu" "F.Mask" "F.Paste")
			(net "LPC_CPU_NODE1_FRAME_L_R")
		)
	)
	(footprint ""
		(layer "F.Cu")
		(at 128.517904 -161.243772 180)
		(property "Reference" "R648"
			(at 61.71184 -109.770926 0)
			(unlocked yes)
			(layer "F.SilkS")
			(effects
				(font
					(size 0.7874 0.5842)
					(thickness 0.1524)
				)
				(justify left)
			)
		)
		(property "Value" ""
			(at 0 0 180)
			(layer "F.Fab")
			(effects
				(font
					(size 1.27 1.27)
				)
			)
		)
		(duplicate_pad_numbers_are_jumpers no)
		(fp_line
			(start 0.7874 0.4064)
			(end -0.7874 0.4064)
			(stroke
				(width 0.1524)
				(type default)
			)
			(layer "F.SilkS")
		)
		(fp_line
			(start 0.7874 -0.4064)
			(end 0.7874 0.4064)
			(stroke
				(width 0.1524)
				(type default)
			)
			(layer "F.SilkS")
		)
		(fp_line
			(start -0.7874 0.4064)
			(end -0.7874 -0.4064)
			(stroke
				(width 0.1524)
				(type default)
			)
			(layer "F.SilkS")
		)
		(fp_line
			(start -0.7874 -0.4064)
			(end 0.7874 -0.4064)
			(stroke
				(width 0.1524)
				(type default)
			)
			(layer "F.SilkS")
		)
		(fp_poly
			(pts
				(xy -0.508 0.2794) (xy -0.508 0.2286) (xy -0.635 0.2286) (xy -0.635 -0.254) (xy -0.5334 -0.254)
				(xy -0.5334 -0.2794) (xy 0.5334 -0.2794) (xy 0.5334 -0.254) (xy 0.635 -0.254) (xy 0.635 0.254) (xy 0.5334 0.254)
				(xy 0.5334 0.2794)
			)
			(stroke
				(width 0)
				(type default)
			)
			(fill no)
			(layer "F.CrtYd")
		)
		(pad "1" smd rect
			(at 0.40005 0 180)
			(size 0.4572 0.508)
			(layers "F.Cu" "F.Mask" "F.Paste")
			(net "I2C_PSU3_SCL")
		)
		(pad "2" smd rect
			(at -0.40005 0 180)
			(size 0.4572 0.508)
			(layers "F.Cu" "F.Mask" "F.Paste")
			(net "I2C_PSU3_SCL_MOS")
		)
	)
	(footprint ""
		(layer "F.Cu")
		(at 187.644278 -145.587466 -90)
		(property "Reference" "Q16"
			(at -4.113784 0.771906 0)
			(unlocked yes)
			(layer "F.SilkS")
			(effects
				(font
					(size 0.7874 0.5842)
					(thickness 0.1524)
				)
				(justify left)
			)
		)
		(property "Value" ""
			(at 0 0 270)
			(layer "F.Fab")
			(effects
				(font
					(size 1.27 1.27)
				)
			)
		)
		(duplicate_pad_numbers_are_jumpers no)
		(fp_line
			(start -3.3528 1.651)
			(end 3.3528 1.651)
			(stroke
				(width 0.1524)
				(type default)
			)
			(layer "F.SilkS")
		)
		(fp_line
			(start 3.3528 1.651)
			(end 3.3528 -1.651)
			(stroke
				(width 0.1524)
				(type default)
			)
			(layer "F.SilkS")
		)
		(fp_line
			(start -3.3528 -1.651)
			(end -3.3528 1.651)
			(stroke
				(width 0.1524)
				(type default)
			)
			(layer "F.SilkS")
		)
		(fp_line
			(start 3.3528 -1.651)
			(end -3.3528 -1.651)
			(stroke
				(width 0.1524)
				(type default)
			)
			(layer "F.SilkS")
		)
		(fp_poly
			(pts
				(xy -3.048 3.8354) (xy -3.048 1.8796) (xy -3.3528 1.8796) (xy -3.3528 -1.8796) (xy -1.905 -1.8796)
				(xy -1.905 -3.8354) (xy 1.905 -3.8354) (xy 1.905 -1.8796) (xy 3.3528 -1.8796) (xy 3.3528 1.8796)
				(xy 3.048 1.8796) (xy 3.048 3.8354)
			)
			(stroke
				(width 0)
				(type default)
			)
			(fill no)
			(layer "F.CrtYd")
		)
		(pad "1" smd rect
			(at -2.286 2.8321 270)
			(size 1.4986 2.0066)
			(layers "F.Cu" "F.Mask" "F.Paste")
			(net "LAN2_CTRL_P1V9")
		)
		(pad "2" smd rect
			(at 0 2.8321 270)
			(size 1.4986 2.0066)
			(layers "F.Cu" "F.Mask" "F.Paste")
			(net "P1V9_LAN2")
		)
		(pad "3" smd rect
			(at 2.286 2.8321 270)
			(size 1.4986 2.0066)
			(layers "F.Cu" "F.Mask" "F.Paste")
			(net "P3V3_NODE1")
		)
		(pad "4" smd rect
			(at 0 -2.8321)
			(size 2.0066 3.81)
			(layers "F.Cu" "F.Mask" "F.Paste")
			(net "P1V9_LAN2")
		)
	)
	(footprint ""
		(layer "F.Cu")
		(at 64.391794 -14.892782 -90)
		(property "Reference" "PC78"
			(at 0.018034 9.23036 90)
			(unlocked yes)
			(layer "F.SilkS")
			(effects
				(font
					(size 0.7874 0.5842)
					(thickness 0.1524)
				)
				(justify left)
			)
		)
		(property "Value" ""
			(at 0 0 270)
			(layer "F.Fab")
			(effects
				(font
					(size 1.27 1.27)
				)
			)
		)
		(duplicate_pad_numbers_are_jumpers no)
		(fp_line
			(start -0.7874 0.4064)
			(end -0.7874 -0.4064)
			(stroke
				(width 0.1524)
				(type default)
			)
			(layer "F.SilkS")
		)
		(fp_line
			(start 0.7874 0.4064)
			(end -0.7874 0.4064)
			(stroke
				(width 0.1524)
				(type default)
			)
			(layer "F.SilkS")
		)
		(fp_line
			(start 0 0.381)
			(end 0 -0.381)
			(stroke
				(width 0.1524)
				(type default)
			)
			(layer "F.SilkS")
		)
		(fp_line
			(start -0.7874 -0.4064)
			(end 0.7874 -0.4064)
			(stroke
				(width 0.1524)
				(type default)
			)
			(layer "F.SilkS")
		)
		(fp_line
			(start 0.7874 -0.4064)
			(end 0.7874 0.4064)
			(stroke
				(width 0.1524)
				(type default)
			)
			(layer "F.SilkS")
		)
		(fp_poly
			(pts
				(xy -0.5334 0.254) (xy -0.635 0.254) (xy -0.635 0.2286) (xy -0.635 -0.254) (xy -0.5334 -0.254) (xy -0.5334 -0.2794)
				(xy 0.5334 -0.2794) (xy 0.5334 -0.254) (xy 0.635 -0.254) (xy 0.635 0.254) (xy 0.5334 0.254) (xy 0.5334 0.2794)
				(xy -0.508 0.2794) (xy -0.5334 0.2794)
			)
			(stroke
				(width 0)
				(type default)
			)
			(fill no)
			(layer "F.CrtYd")
		)
		(pad "1" smd rect
			(at 0.40005 0 270)
			(size 0.4572 0.508)
			(layers "F.Cu" "F.Mask" "F.Paste")
			(net "PV_VDDR_NODE1")
		)
		(pad "2" smd rect
			(at -0.40005 0 270)
			(size 0.4572 0.508)
			(layers "F.Cu" "F.Mask" "F.Paste")
			(net "GND")
		)
	)
	(footprint ""
		(layer "F.Cu")
		(at 116.872258 -149.24278 180)
		(property "Reference" "R1249"
			(at 3.789172 -1.870456 0)
			(unlocked yes)
			(layer "F.SilkS")
			(effects
				(font
					(size 0.635 0.4064)
					(thickness 0.1524)
				)
				(justify left)
			)
		)
		(property "Value" ""
			(at 0 0 180)
			(layer "F.Fab")
			(effects
				(font
					(size 1.27 1.27)
				)
			)
		)
		(duplicate_pad_numbers_are_jumpers no)
		(fp_line
			(start 1.905 0.8636)
			(end -1.905 0.8636)
			(stroke
				(width 0.1524)
				(type default)
			)
			(layer "F.SilkS")
		)
		(fp_line
			(start 1.905 -0.8636)
			(end 1.905 0.8636)
			(stroke
				(width 0.1524)
				(type default)
			)
			(layer "F.SilkS")
		)
		(fp_line
			(start -1.905 0.8636)
			(end -1.905 -0.8636)
			(stroke
				(width 0.1524)
				(type default)
			)
			(layer "F.SilkS")
		)
		(fp_line
			(start -1.905 -0.8636)
			(end 1.905 -0.8636)
			(stroke
				(width 0.1524)
				(type default)
			)
			(layer "F.SilkS")
		)
		(fp_poly
			(pts
				(xy 1.524 0.6858) (xy 1.524 -0.6858) (xy 1.524 -0.7366) (xy -1.524 -0.7366) (xy -1.524 -0.6858)
				(xy -1.524 0.6858) (xy -1.524 0.7366) (xy 1.524 0.7366)
			)
			(stroke
				(width 0)
				(type default)
			)
			(fill no)
			(layer "F.CrtYd")
		)
		(pad "1" smd rect
			(at 0.94996 0 180)
			(size 1.1176 1.3716)
			(layers "F.Cu" "F.Mask" "F.Paste")
			(net "P12V_AUX")
		)
		(pad "2" smd rect
			(at -0.94996 0 180)
			(size 1.1176 1.3716)
			(layers "F.Cu" "F.Mask" "F.Paste")
			(net "N52998325")
		)
	)
)
